(kicad_pcb
	(version 20241229)
	(generator "pcbnew")
	(generator_version "9.0")
	(general
		(thickness 1.294)
		(legacy_teardrops no)
	)
	(paper "A3")
	(title_block
		(title "Kintex 410T devboard")
		(date "2024-04-03")
		(rev "1.1.2")
		(comment 9 "footprints 200-200 of 975")
	)
	(layers
		(0 "F.Cu" mixed)
		(4 "In1.Cu" power)
		(6 "In2.Cu" power)
		(8 "In3.Cu" mixed)
		(10 "In4.Cu" power)
		(12 "In5.Cu" mixed)
		(14 "In6.Cu" power)
		(16 "In7.Cu" mixed)
		(18 "In8.Cu" power)
		(2 "B.Cu" mixed)
		(9 "F.Adhes" user "F.Adhesive")
		(11 "B.Adhes" user "B.Adhesive")
		(13 "F.Paste" user)
		(15 "B.Paste" user)
		(5 "F.SilkS" user "F.Silkscreen")
		(7 "B.SilkS" user "B.Silkscreen")
		(1 "F.Mask" user)
		(3 "B.Mask" user)
		(17 "Dwgs.User" user "User.Drawings")
		(19 "Cmts.User" user "User.Comments")
		(21 "Eco1.User" user "User.Eco1")
		(23 "Eco2.User" user "User.Eco2")
		(25 "Edge.Cuts" user)
		(27 "Margin" user)
		(31 "F.CrtYd" user "F.Courtyard")
		(29 "B.CrtYd" user "B.Courtyard")
		(35 "F.Fab" user)
		(33 "B.Fab" user)
	)
	(footprint "antmicro-footprints:SW_DIP_SPSTx08_Slide_Copal_CVS-08xB_W5.9mm_P1mm"
		(layer "F.Cu")
		(at 179.27 185.69 -90)
		(descr "SMD 8x-dip-switch SPST Copal_CVS-08xB, Slide, row spacing 5.9 mm (232 mils), body size  (see http://www.nidec-copal-electronics.com/e/catalog/switch/cvs.pdf)")
		(tags "SMD DIP Switch SPST Slide 5.9mm 232mil")
		(property "Reference" "SW3"
			(at -3.74 1.17 180)
			(layer "F.SilkS")
			(effects
				(font
					(size 0.7 0.7)
					(thickness 0.15)
				)
				(justify left bottom)
			)
		)
		(property "Value" "SW_CVS-08TB"
			(at -14.59 6.29 270)
			(layer "F.Fab")
			(effects
				(font
					(size 0.7 0.7)
					(thickness 0.15)
				)
				(justify left bottom)
			)
		)
		(property "Description" "DIP / SIP Switch, 8 Circuits, Slide, Surface Mount, SPST, 6 V, 100 mA"
			(at 0 0 270)
			(layer "F.Fab")
			(hide yes)
			(effects
				(font
					(size 1.27 1.27)
					(thickness 0.15)
				)
			)
		)
		(property "Author" "Antmicro"
			(at -6.42 364.96 0)
			(layer "F.Fab")
			(hide yes)
			(effects
				(font
					(size 1 1)
					(thickness 0.15)
				)
			)
		)
		(property "License" "Apache-2.0"
			(at -6.42 364.96 0)
			(layer "F.Fab")
			(hide yes)
			(effects
				(font
					(size 1 1)
					(thickness 0.15)
				)
			)
		)
		(property "MPN" "CVS-08TB"
			(at -6.42 364.96 0)
			(layer "F.Fab")
			(hide yes)
			(effects
				(font
					(size 1 1)
					(thickness 0.15)
				)
			)
		)
		(property "Manufacturer" "Nidec Components"
			(at -6.42 364.96 0)
			(layer "F.Fab")
			(hide yes)
			(effects
				(font
					(size 1 1)
					(thickness 0.15)
				)
			)
		)
		(sheetname "USB PHY")
		(sheetfile "usb-phy.kicad_sch")
		(attr smd)
		(fp_line
			(start -1.561 4.91)
			(end 1.56 4.91)
			(stroke
				(width 0.15)
				(type solid)
			)
			(layer "F.SilkS")
		)
		(fp_line
			(start -1.561 -4.912)
			(end 1.56 -4.912)
			(stroke
				(width 0.15)
				(type solid)
			)
			(layer "F.SilkS")
		)
		(fp_circle
			(center -3.31 -4.2)
			(end -3.261 -4.2)
			(stroke
				(width 0.15)
				(type solid)
			)
			(fill yes)
			(layer "F.SilkS")
		)
		(fp_rect
			(start -3.601 -5)
			(end 3.598 4.998)
			(stroke
				(width 0.05)
				(type solid)
			)
			(fill no)
			(layer "F.CrtYd")
		)
		(fp_line
			(start -2.351 4.498)
			(end -2.351 -3.5)
			(stroke
				(width 0.15)
				(type solid)
			)
			(layer "F.Fab")
		)
		(fp_line
			(start 2.35 4.498)
			(end -2.351 4.498)
			(stroke
				(width 0.15)
				(type solid)
			)
			(layer "F.Fab")
		)
		(fp_line
			(start -1 3.749)
			(end -0.335 3.749)
			(stroke
				(width 0.15)
				(type solid)
			)
			(layer "F.Fab")
		)
		(fp_line
			(start -1 3.749)
			(end 0.998 3.749)
			(stroke
				(width 0.15)
				(type solid)
			)
			(layer "F.Fab")
		)
		(fp_line
			(start 0.998 3.749)
			(end 0.998 3.249)
			(stroke
				(width 0.15)
				(type solid)
			)
			(layer "F.Fab")
		)
		(fp_line
			(start -1 3.648)
			(end -0.335 3.648)
			(stroke
				(width 0.15)
				(type solid)
			)
			(layer "F.Fab")
		)
		(fp_line
			(start -1 3.548)
			(end -0.335 3.548)
			(stroke
				(width 0.15)
				(type solid)
			)
			(layer "F.Fab")
		)
		(fp_line
			(start -1 3.45)
			(end -0.335 3.45)
			(stroke
				(width 0.15)
				(type solid)
			)
			(layer "F.Fab")
		)
		(fp_line
			(start -1 3.35)
			(end -0.335 3.35)
			(stroke
				(width 0.15)
				(type solid)
			)
			(layer "F.Fab")
		)
		(fp_line
			(start -1 3.249)
			(end -1 3.749)
			(stroke
				(width 0.15)
				(type solid)
			)
			(layer "F.Fab")
		)
		(fp_line
			(start -0.335 3.249)
			(end -0.335 3.749)
			(stroke
				(width 0.15)
				(type solid)
			)
			(layer "F.Fab")
		)
		(fp_line
			(start 0.998 3.249)
			(end -1 3.249)
			(stroke
				(width 0.15)
				(type solid)
			)
			(layer "F.Fab")
		)
		(fp_line
			(start -1 2.749)
			(end -0.335 2.749)
			(stroke
				(width 0.15)
				(type solid)
			)
			(layer "F.Fab")
		)
		(fp_line
			(start -1 2.749)
			(end 0.998 2.749)
			(stroke
				(width 0.15)
				(type solid)
			)
			(layer "F.Fab")
		)
		(fp_line
			(start 0.998 2.749)
			(end 0.998 2.249)
			(stroke
				(width 0.15)
				(type solid)
			)
			(layer "F.Fab")
		)
		(fp_line
			(start -1 2.648)
			(end -0.335 2.648)
			(stroke
				(width 0.15)
				(type solid)
			)
			(layer "F.Fab")
		)
		(fp_line
			(start -1 2.548)
			(end -0.335 2.548)
			(stroke
				(width 0.15)
				(type solid)
			)
			(layer "F.Fab")
		)
		(fp_line
			(start -1 2.45)
			(end -0.335 2.45)
			(stroke
				(width 0.15)
				(type solid)
			)
			(layer "F.Fab")
		)
		(fp_line
			(start -1 2.35)
			(end -0.335 2.35)
			(stroke
				(width 0.15)
				(type solid)
			)
			(layer "F.Fab")
		)
		(fp_line
			(start -1 2.249)
			(end -1 2.749)
			(stroke
				(width 0.15)
				(type solid)
			)
			(layer "F.Fab")
		)
		(fp_line
			(start -0.335 2.249)
			(end -0.335 2.749)
			(stroke
				(width 0.15)
				(type solid)
			)
			(layer "F.Fab")
		)
		(fp_line
			(start 0.998 2.249)
			(end -1 2.249)
			(stroke
				(width 0.15)
				(type solid)
			)
			(layer "F.Fab")
		)
		(fp_line
			(start -1 1.749)
			(end -0.335 1.749)
			(stroke
				(width 0.15)
				(type solid)
			)
			(layer "F.Fab")
		)
		(fp_line
			(start -1 1.749)
			(end 0.998 1.749)
			(stroke
				(width 0.15)
				(type solid)
			)
			(layer "F.Fab")
		)
		(fp_line
			(start 0.998 1.749)
			(end 0.998 1.249)
			(stroke
				(width 0.15)
				(type solid)
			)
			(layer "F.Fab")
		)
		(fp_line
			(start -1 1.648)
			(end -0.335 1.648)
			(stroke
				(width 0.15)
				(type solid)
			)
			(layer "F.Fab")
		)
		(fp_line
			(start -1 1.55)
			(end -0.335 1.55)
			(stroke
				(width 0.15)
				(type solid)
			)
			(layer "F.Fab")
		)
		(fp_line
			(start -1 1.449)
			(end -0.335 1.449)
			(stroke
				(width 0.15)
				(type solid)
			)
			(layer "F.Fab")
		)
		(fp_line
			(start -1 1.35)
			(end -0.335 1.35)
			(stroke
				(width 0.15)
				(type solid)
			)
			(layer "F.Fab")
		)
		(fp_line
			(start -1 1.249)
			(end -1 1.749)
			(stroke
				(width 0.15)
				(type solid)
			)
			(layer "F.Fab")
		)
		(fp_line
			(start -0.335 1.249)
			(end -0.335 1.749)
			(stroke
				(width 0.15)
				(type solid)
			)
			(layer "F.Fab")
		)
		(fp_line
			(start 0.998 1.249)
			(end -1 1.249)
			(stroke
				(width 0.15)
				(type solid)
			)
			(layer "F.Fab")
		)
		(fp_line
			(start -1 0.748)
			(end -0.335 0.748)
			(stroke
				(width 0.15)
				(type solid)
			)
			(layer "F.Fab")
		)
		(fp_line
			(start -1 0.748)
			(end 0.998 0.748)
			(stroke
				(width 0.15)
				(type solid)
			)
			(layer "F.Fab")
		)
		(fp_line
			(start 0.998 0.748)
			(end 0.998 0.248)
			(stroke
				(width 0.15)
				(type solid)
			)
			(layer "F.Fab")
		)
		(fp_line
			(start -1 0.65)
			(end -0.335 0.65)
			(stroke
				(width 0.15)
				(type solid)
			)
			(layer "F.Fab")
		)
		(fp_line
			(start -1 0.55)
			(end -0.335 0.55)
			(stroke
				(width 0.15)
				(type solid)
			)
			(layer "F.Fab")
		)
		(fp_line
			(start -1 0.45)
			(end -0.335 0.45)
			(stroke
				(width 0.15)
				(type solid)
			)
			(layer "F.Fab")
		)
		(fp_line
			(start -1 0.349)
			(end -0.335 0.349)
			(stroke
				(width 0.15)
				(type solid)
			)
			(layer "F.Fab")
		)
		(fp_line
			(start -1 0.248)
			(end -1 0.748)
			(stroke
				(width 0.15)
				(type solid)
			)
			(layer "F.Fab")
		)
		(fp_line
			(start -0.335 0.248)
			(end -0.335 0.748)
			(stroke
				(width 0.15)
				(type solid)
			)
			(layer "F.Fab")
		)
		(fp_line
			(start 0.998 0.248)
			(end -1 0.248)
			(stroke
				(width 0.15)
				(type solid)
			)
			(layer "F.Fab")
		)
		(fp_line
			(start -1 -0.25)
			(end 0.998 -0.25)
			(stroke
				(width 0.15)
				(type solid)
			)
			(layer "F.Fab")
		)
		(fp_line
			(start 0.998 -0.25)
			(end 0.998 -0.75)
			(stroke
				(width 0.15)
				(type solid)
			)
			(layer "F.Fab")
		)
		(fp_line
			(start -1 -0.351)
			(end -0.335 -0.351)
			(stroke
				(width 0.15)
				(type solid)
			)
			(layer "F.Fab")
		)
		(fp_line
			(start -1 -0.452)
			(end -0.335 -0.452)
			(stroke
				(width 0.15)
				(type solid)
			)
			(layer "F.Fab")
		)
		(fp_line
			(start -1 -0.552)
			(end -0.335 -0.552)
			(stroke
				(width 0.15)
				(type solid)
			)
			(layer "F.Fab")
		)
		(fp_line
			(start -1 -0.652)
			(end -0.335 -0.652)
			(stroke
				(width 0.15)
				(type solid)
			)
			(layer "F.Fab")
		)
		(fp_line
			(start -1 -0.75)
			(end -1 -0.25)
			(stroke
				(width 0.15)
				(type solid)
			)
			(layer "F.Fab")
		)
		(fp_line
			(start -0.335 -0.75)
			(end -0.335 -0.25)
			(stroke
				(width 0.15)
				(type solid)
			)
			(layer "F.Fab")
		)
		(fp_line
			(start 0.998 -0.75)
			(end -1 -0.75)
			(stroke
				(width 0.15)
				(type solid)
			)
			(layer "F.Fab")
		)
		(fp_line
			(start -1 -1.25)
			(end 0.998 -1.25)
			(stroke
				(width 0.15)
				(type solid)
			)
			(layer "F.Fab")
		)
		(fp_line
			(start 0.998 -1.25)
			(end 0.998 -1.75)
			(stroke
				(width 0.15)
				(type solid)
			)
			(layer "F.Fab")
		)
		(fp_line
			(start -1 -1.351)
			(end -0.335 -1.351)
			(stroke
				(width 0.15)
				(type solid)
			)
			(layer "F.Fab")
		)
		(fp_line
			(start -1 -1.45)
			(end -0.335 -1.45)
			(stroke
				(width 0.15)
				(type solid)
			)
			(layer "F.Fab")
		)
		(fp_line
			(start -1 -1.551)
			(end -0.335 -1.551)
			(stroke
				(width 0.15)
				(type solid)
			)
			(layer "F.Fab")
		)
		(fp_line
			(start -1 -1.651)
			(end -0.335 -1.651)
			(stroke
				(width 0.15)
				(type solid)
			)
			(layer "F.Fab")
		)
		(fp_line
			(start -1 -1.75)
			(end -1 -1.25)
			(stroke
				(width 0.15)
				(type solid)
			)
			(layer "F.Fab")
		)
		(fp_line
			(start -0.335 -1.75)
			(end -0.335 -1.25)
			(stroke
				(width 0.15)
				(type solid)
			)
			(layer "F.Fab")
		)
		(fp_line
			(start 0.998 -1.75)
			(end -1 -1.75)
			(stroke
				(width 0.15)
				(type solid)
			)
			(layer "F.Fab")
		)
		(fp_line
			(start -1 -2.25)
			(end 0.998 -2.25)
			(stroke
				(width 0.15)
				(type solid)
			)
			(layer "F.Fab")
		)
		(fp_line
			(start 0.998 -2.25)
			(end 0.998 -2.75)
			(stroke
				(width 0.15)
				(type solid)
			)
			(layer "F.Fab")
		)
		(fp_line
			(start -1 -2.351)
			(end -0.335 -2.351)
			(stroke
				(width 0.15)
				(type solid)
			)
			(layer "F.Fab")
		)
		(fp_line
			(start -1 -2.452)
			(end -0.335 -2.452)
			(stroke
				(width 0.15)
				(type solid)
			)
			(layer "F.Fab")
		)
		(fp_line
			(start -1 -2.551)
			(end -0.335 -2.551)
			(stroke
				(width 0.15)
				(type solid)
			)
			(layer "F.Fab")
		)
		(fp_line
			(start -1 -2.65)
			(end -0.335 -2.65)
			(stroke
				(width 0.15)
				(type solid)
			)
			(layer "F.Fab")
		)
		(fp_line
			(start -1 -2.75)
			(end -1 -2.25)
			(stroke
				(width 0.15)
				(type solid)
			)
			(layer "F.Fab")
		)
		(fp_line
			(start -0.335 -2.75)
			(end -0.335 -2.25)
			(stroke
				(width 0.15)
				(type solid)
			)
			(layer "F.Fab")
		)
		(fp_line
			(start 0.998 -2.75)
			(end -1 -2.75)
			(stroke
				(width 0.15)
				(type solid)
			)
			(layer "F.Fab")
		)
		(fp_line
			(start -1 -3.25)
			(end 0.998 -3.25)
			(stroke
				(width 0.15)
				(type solid)
			)
			(layer "F.Fab")
		)
		(fp_line
			(start 0.998 -3.25)
			(end 0.998 -3.75)
			(stroke
				(width 0.15)
				(type solid)
			)
			(layer "F.Fab")
		)
		(fp_line
			(start -1 -3.351)
			(end -0.335 -3.351)
			(stroke
				(width 0.15)
				(type solid)
			)
			(layer "F.Fab")
		)
		(fp_line
			(start -1 -3.451)
			(end -0.335 -3.451)
			(stroke
				(width 0.15)
				(type solid)
			)
			(layer "F.Fab")
		)
		(fp_line
			(start -2.351 -3.5)
			(end -1.351 -4.5)
			(stroke
				(width 0.15)
				(type solid)
			)
			(layer "F.Fab")
		)
		(fp_line
			(start -1 -3.551)
			(end -0.335 -3.551)
			(stroke
				(width 0.15)
				(type solid)
			)
			(layer "F.Fab")
		)
		(fp_line
			(start -1 -3.65)
			(end -0.335 -3.65)
			(stroke
				(width 0.15)
				(type solid)
			)
			(layer "F.Fab")
		)
		(fp_line
			(start -1 -3.75)
			(end -1 -3.25)
			(stroke
				(width 0.15)
				(type solid)
			)
			(layer "F.Fab")
		)
		(fp_line
			(start -0.335 -3.75)
			(end -0.335 -3.25)
			(stroke
				(width 0.15)
				(type solid)
			)
			(layer "F.Fab")
		)
		(fp_line
			(start 0.998 -3.75)
			(end -1 -3.75)
			(stroke
				(width 0.15)
				(type solid)
			)
			(layer "F.Fab")
		)
		(fp_line
			(start -1.351 -4.5)
			(end 2.35 -4.5)
			(stroke
				(width 0.15)
				(type solid)
			)
			(layer "F.Fab")
		)
		(fp_line
			(start 2.35 -4.5)
			(end 2.35 4.498)
			(stroke
				(width 0.15)
				(type solid)
			)
			(layer "F.Fab")
		)
		(fp_text user "on"
			(at -1.56 0.69 0)
			(layer "F.Fab")
			(effects
				(font
					(size 0.7 0.7)
					(thickness 0.15)
				)
				(justify left bottom)
			)
		)
		(pad "1" smd rect
			(at -2.952 -3.5 270)
			(size 1.2 0.5)
			(layers "F.Cu" "F.Mask" "F.Paste")
			(net 1209 "unconnected-(SW3-Pad1)")
			(pinfunction "1")
			(pintype "passive+no_connect")
		)
		(pad "2" smd rect
			(at -2.952 -2.5 270)
			(size 1.2 0.5)
			(layers "F.Cu" "F.Mask" "F.Paste")
			(net 1210 "unconnected-(SW3-Pad2)")
			(pinfunction "2")
			(pintype "passive+no_connect")
		)
		(pad "3" smd rect
			(at -2.952 -1.5 270)
			(size 1.2 0.5)
			(layers "F.Cu" "F.Mask" "F.Paste")
			(net 1393 "/I2C.QDCDC2_SCL")
			(pinfunction "3")
			(pintype "passive")
		)
		(pad "4" smd rect
			(at -2.952 -0.5 270)
			(size 1.2 0.5)
			(layers "F.Cu" "F.Mask" "F.Paste")
			(net 1394 "/I2C.QDCDC1_SCL")
			(pinfunction "4")
			(pintype "passive")
		)
		(pad "5" smd rect
			(at -2.952 0.498 270)
			(size 1.2 0.5)
			(layers "F.Cu" "F.Mask" "F.Paste")
			(net 1023 "/USB PHY/BDBUS0")
			(pinfunction "5")
			(pintype "passive")
		)
		(pad "6" smd rect
			(at -2.952 1.499 270)
			(size 1.2 0.5)
			(layers "F.Cu" "F.Mask" "F.Paste")
			(net 1024 "/USB PHY/BDBUS1")
			(pinfunction "6")
			(pintype "passive")
		)
		(pad "7" smd rect
			(at -2.952 2.499 270)
			(size 1.2 0.5)
			(layers "F.Cu" "F.Mask" "F.Paste")
			(net 1025 "/USB PHY/BDBUS2")
			(pinfunction "7")
			(pintype "passive")
		)
		(pad "8" smd rect
			(at -2.952 3.499 270)
			(size 1.2 0.5)
			(layers "F.Cu" "F.Mask" "F.Paste")
			(net 799 "FTDI_DIS")
			(pinfunction "8")
			(pintype "passive")
		)
		(pad "9" smd rect
			(at 2.95 3.499 270)
			(size 1.2 0.5)
			(layers "F.Cu" "F.Mask" "F.Paste")
			(net 1 "GND")
			(pinfunction "9")
			(pintype "passive")
		)
		(pad "10" smd rect
			(at 2.95 2.499 270)
			(size 1.2 0.5)
			(layers "F.Cu" "F.Mask" "F.Paste")
			(net 942 "/USB PHY/FTDI_SDA_IN")
			(pinfunction "10")
			(pintype "passive")
		)
		(pad "11" smd rect
			(at 2.95 1.499 270)
			(size 1.2 0.5)
			(layers "F.Cu" "F.Mask" "F.Paste")
			(net 1047 "/USB PHY/FTDI_SDA_OUT")
			(pinfunction "11")
			(pintype "passive")
		)
		(pad "12" smd rect
			(at 2.95 0.498 270)
			(size 1.2 0.5)
			(layers "F.Cu" "F.Mask" "F.Paste")
			(net 941 "/USB PHY/FTDI_SCL")
			(pinfunction "12")
			(pintype "passive")
		)
		(pad "13" smd rect
			(at 2.95 -0.5 270)
			(size 1.2 0.5)
			(layers "F.Cu" "F.Mask" "F.Paste")
			(net 1338 "/I2C.SCL")
			(pinfunction "13")
			(pintype "passive")
		)
		(pad "14" smd rect
			(at 2.95 -1.5 270)
			(size 1.2 0.5)
			(layers "F.Cu" "F.Mask" "F.Paste")
			(net 1338 "/I2C.SCL")
			(pinfunction "14")
			(pintype "passive")
		)
		(pad "15" smd rect
			(at 2.95 -2.5 270)
			(size 1.2 0.5)
			(layers "F.Cu" "F.Mask" "F.Paste")
			(net 1211 "unconnected-(SW3-Pad15)")
			(pinfunction "15")
			(pintype "passive+no_connect")
		)
		(pad "16" smd rect
			(at 2.95 -3.5 270)
			(size 1.2 0.5)
			(layers "F.Cu" "F.Mask" "F.Paste")
			(net 1212 "unconnected-(SW3-Pad16)")
			(pinfunction "16")
			(pintype "passive+no_connect")
		)
		(pad "17" smd rect
			(at -2.15 -4.5 270)
			(size 0.7 0.7)
			(layers "F.Cu" "F.Mask" "F.Paste")
			(net 1 "GND")
			(pinfunction "17")
			(pintype "power_in")
		)
		(pad "17" smd rect
			(at -2.15 4.498 270)
			(size 0.7 0.7)
			(layers "F.Cu" "F.Mask" "F.Paste")
			(net 1 "GND")
			(pinfunction "17")
			(pintype "power_in")
		)
		(pad "17" smd rect
			(at 2.148 -4.5 270)
			(size 0.7 0.7)
			(layers "F.Cu" "F.Mask" "F.Paste")
			(net 1 "GND")
			(pinfunction "17")
			(pintype "power_in")
		)
		(pad "17" smd rect
			(at 2.148 4.498 270)
			(size 0.7 0.7)
			(layers "F.Cu" "F.Mask" "F.Paste")
			(net 1 "GND")
			(pinfunction "17")
			(pintype "power_in")
		)
	)
)
